FILE_TYPE = MACRO_DRAWING;
SET COLOR_WIRE YELLOW;
SET COLOR_PROP ORANGE;
SET COLOR_DOT WHITE;
SET COLOR_ARC YELLOW;
SET COLOR_BODY GREEN;
SET COLOR_NOTE PURPLE;
SET PROP_DISPLAY VALUE;
SET PAGE_NUMBER P396;
FORCEADD PT5161LRS..8
(-7825 3950);
FORCEPROP 1 LAST LOCATION U6015
J 0
(-8175 5575);
DISPLAY 0.723404 (-8175 5575);
PAINT GREEN (-8175 5575);
FORCEPROP 0 LAST $SEC 8
J 0
(-8175 5725);
DISPLAY 0.680851 (-8175 5725);
PAINT MONO (-8175 5725);
DISPLAY INVISIBLE (-8175 5725);
FORCEPROP 0 LAST CDS_SEC 8
J 0
(-8175 5725);
DISPLAY 0.680851 (-8175 5725);
DISPLAY INVISIBLE (-8175 5725);
FORCEPROP 0 LASTPIN (-7375 5100) $PN R35
J 0
(-7365 5110);
DISPLAY 0.680851 (-7365 5110);
PAINT MONO (-7365 5110);
FORCEPROP 0 LASTPIN (-7375 4750) $PN AB35
J 0
(-7365 4760);
DISPLAY 0.680851 (-7365 4760);
PAINT MONO (-7365 4760);
FORCEPROP 0 LASTPIN (-7375 4400) $PN AJ35
J 0
(-7365 4410);
DISPLAY 0.680851 (-7365 4410);
PAINT MONO (-7365 4410);
FORCEPROP 0 LASTPIN (-7375 4050) $PN AT35
J 0
(-7365 4060);
DISPLAY 0.680851 (-7365 4060);
PAINT MONO (-7365 4060);
FORCEPROP 0 LASTPIN (-7375 3700) $PN BC35
J 0
(-7365 3710);
DISPLAY 0.680851 (-7365 3710);
PAINT MONO (-7365 3710);
FORCEPROP 0 LASTPIN (-7375 3350) $PN BK35
J 0
(-7365 3360);
DISPLAY 0.680851 (-7365 3360);
PAINT MONO (-7365 3360);
FORCEPROP 0 LASTPIN (-7375 3000) $PN BU35
J 0
(-7365 3010);
DISPLAY 0.680851 (-7365 3010);
PAINT MONO (-7365 3010);
FORCEPROP 0 LASTPIN (-7375 2650) $PN CD35
J 0
(-7365 2660);
DISPLAY 0.680851 (-7365 2660);
PAINT MONO (-7365 2660);
FORCEPROP 0 LASTPIN (-7375 5200) $PN N34
J 0
(-7365 5210);
DISPLAY 0.680851 (-7365 5210);
PAINT MONO (-7365 5210);
FORCEPROP 0 LASTPIN (-7375 4850) $PN Y34
J 0
(-7365 4860);
DISPLAY 0.680851 (-7365 4860);
PAINT MONO (-7365 4860);
FORCEPROP 0 LASTPIN (-7375 4500) $PN AG34
J 0
(-7365 4510);
DISPLAY 0.680851 (-7365 4510);
PAINT MONO (-7365 4510);
FORCEPROP 0 LASTPIN (-7375 4150) $PN AP34
J 0
(-7365 4160);
DISPLAY 0.680851 (-7365 4160);
PAINT MONO (-7365 4160);
FORCEPROP 0 LASTPIN (-7375 3800) $PN BA34
J 0
(-7365 3810);
DISPLAY 0.680851 (-7365 3810);
PAINT MONO (-7365 3810);
FORCEPROP 0 LASTPIN (-7375 3450) $PN BH34
J 0
(-7365 3460);
DISPLAY 0.680851 (-7365 3460);
PAINT MONO (-7365 3460);
FORCEPROP 0 LASTPIN (-7375 3100) $PN BR34
J 0
(-7365 3110);
DISPLAY 0.680851 (-7365 3110);
PAINT MONO (-7365 3110);
FORCEPROP 0 LASTPIN (-7375 2750) $PN CB34
J 0
(-7365 2760);
DISPLAY 0.680851 (-7365 2760);
PAINT MONO (-7365 2760);
FORCEPROP 1 LAST MATERIAL IC
J 0
(-8175 5425);
DISPLAY 0.723404 (-8175 5425);
PAINT GREEN (-8175 5425);
FORCEPROP 2 LAST PART_TYPE SMLF
J 0
(-8175 5675);
DISPLAY 0.680851 (-8175 5675);
FORCEPROP 2 LAST VALUE PT5161LRS
J 0
(-8175 5625);
DISPLAY 0.680851 (-8175 5625);
FORCEPROP 2 LAST CDS_LIB pure_quanta
J 0
(-7825 3950);
DISPLAY INVISIBLE (-7825 3950);
FORCEPROP 1 LAST CDS_LMAN_SYM_OUTLINE -350,1450,300,-1400
J 0
(-7825 3950);
DISPLAY 0.468085 (-7825 3950);
PAINT GREEN (-7825 3950);
DISPLAY INVISIBLE (-7825 3950);
FORCEPROP 1 LAST NEEDS_NO_SIZE TRUE
J 0
(-7825 3950);
DISPLAY 0.723404 (-7825 3950);
PAINT GREEN (-7825 3950);
DISPLAY INVISIBLE (-7825 3950);
FORCEPROP 1 LAST PATH I1
J 0
(-7825 3950);
DISPLAY 0.723404 (-7825 3950);
PAINT GREEN (-7825 3950);
DISPLAY INVISIBLE (-7825 3950);
FORCEPROP 1 LAST PART_NUMBER AJ051610U03
J 0
(-8175 5500);
DISPLAY 0.723404 (-8175 5500);
PAINT GREEN (-8175 5500);
DISPLAY INVISIBLE (-8175 5500);
FORCEADD TAP..1
(-6800 4150);
FORCEPROP 3 LASTPIN (-6850 4150) SIG_NAME P5E_CPU1_P1_TX_C_DN<12>
J 0
(-6840 4160);
DISPLAY 0.659574 (-6840 4160);
PAINT MONO (-6840 4160);
DISPLAY INVISIBLE (-6840 4160);
FORCEPROP 1 LASTPIN (-6850 4150) BN 12
J 0
(-6862 4158);
DISPLAY 0.680851 (-6862 4158);
PAINT GREEN (-6862 4158);
FORCEPROP 2 LAST CDS_LIB standard
J 0
(-6800 4150);
DISPLAY INVISIBLE (-6800 4150);
FORCEPROP 1 LAST BODY_TYPE PLUMBING
J 0
(-6800 4200);
DISPLAY 0.872340 (-6800 4200);
PAINT GREEN (-6800 4200);
DISPLAY INVISIBLE (-6800 4200);
FORCEPROP 1 LAST HDL_TAP TRUE
J 0
(-6475 4025);
DISPLAY 0.872340 (-6475 4025);
DISPLAY INVISIBLE (-6475 4025);
FORCEPROP 1 LAST PATH I10
J 0
(-6802 4150);
DISPLAY 0.872340 (-6802 4150);
PAINT GREEN (-6802 4150);
DISPLAY INVISIBLE (-6802 4150);
FORCEADD TAP..1
(-6600 4050);
FORCEPROP 3 LASTPIN (-6650 4050) SIG_NAME P5E_CPU1_P1_TX_C_DP<12>
J 0
(-6640 4060);
DISPLAY 0.659574 (-6640 4060);
PAINT MONO (-6640 4060);
DISPLAY INVISIBLE (-6640 4060);
FORCEPROP 1 LASTPIN (-6650 4050) BN 12
J 0
(-6662 4058);
DISPLAY 0.680851 (-6662 4058);
PAINT GREEN (-6662 4058);
FORCEPROP 2 LAST CDS_LIB standard
J 0
(-6600 4050);
DISPLAY INVISIBLE (-6600 4050);
FORCEPROP 1 LAST BODY_TYPE PLUMBING
J 0
(-6600 4100);
DISPLAY 0.872340 (-6600 4100);
PAINT GREEN (-6600 4100);
DISPLAY INVISIBLE (-6600 4100);
FORCEPROP 1 LAST HDL_TAP TRUE
J 0
(-6275 3925);
DISPLAY 0.872340 (-6275 3925);
DISPLAY INVISIBLE (-6275 3925);
FORCEPROP 1 LAST PATH I11
J 0
(-6602 4050);
DISPLAY 0.872340 (-6602 4050);
PAINT GREEN (-6602 4050);
DISPLAY INVISIBLE (-6602 4050);
FORCEADD TAP..1
(-6600 4400);
FORCEPROP 3 LASTPIN (-6650 4400) SIG_NAME P5E_CPU1_P1_TX_C_DP<13>
J 0
(-6640 4410);
DISPLAY 0.659574 (-6640 4410);
PAINT MONO (-6640 4410);
DISPLAY INVISIBLE (-6640 4410);
FORCEPROP 1 LASTPIN (-6650 4400) BN 13
J 0
(-6662 4408);
DISPLAY 0.680851 (-6662 4408);
PAINT GREEN (-6662 4408);
FORCEPROP 2 LAST CDS_LIB standard
J 0
(-6600 4400);
DISPLAY INVISIBLE (-6600 4400);
FORCEPROP 1 LAST BODY_TYPE PLUMBING
J 0
(-6600 4450);
DISPLAY 0.872340 (-6600 4450);
PAINT GREEN (-6600 4450);
DISPLAY INVISIBLE (-6600 4450);
FORCEPROP 1 LAST HDL_TAP TRUE
J 0
(-6275 4275);
DISPLAY 0.872340 (-6275 4275);
DISPLAY INVISIBLE (-6275 4275);
FORCEPROP 1 LAST PATH I12
J 0
(-6602 4400);
DISPLAY 0.872340 (-6602 4400);
PAINT GREEN (-6602 4400);
DISPLAY INVISIBLE (-6602 4400);
FORCEADD TAP..1
(-6800 4500);
FORCEPROP 3 LASTPIN (-6850 4500) SIG_NAME P5E_CPU1_P1_TX_C_DN<13>
J 0
(-6840 4510);
DISPLAY 0.659574 (-6840 4510);
PAINT MONO (-6840 4510);
DISPLAY INVISIBLE (-6840 4510);
FORCEPROP 1 LASTPIN (-6850 4500) BN 13
J 0
(-6862 4508);
DISPLAY 0.680851 (-6862 4508);
PAINT GREEN (-6862 4508);
FORCEPROP 2 LAST CDS_LIB standard
J 0
(-6800 4500);
DISPLAY INVISIBLE (-6800 4500);
FORCEPROP 1 LAST BODY_TYPE PLUMBING
J 0
(-6800 4550);
DISPLAY 0.872340 (-6800 4550);
PAINT GREEN (-6800 4550);
DISPLAY INVISIBLE (-6800 4550);
FORCEPROP 1 LAST HDL_TAP TRUE
J 0
(-6475 4375);
DISPLAY 0.872340 (-6475 4375);
DISPLAY INVISIBLE (-6475 4375);
FORCEPROP 1 LAST PATH I13
J 0
(-6802 4500);
DISPLAY 0.872340 (-6802 4500);
PAINT GREEN (-6802 4500);
DISPLAY INVISIBLE (-6802 4500);
FORCEADD TAP..1
(-6800 4750);
FORCEPROP 3 LASTPIN (-6850 4750) SIG_NAME P5E_CPU1_P1_TX_C_DN<14>
J 0
(-6840 4760);
DISPLAY 0.659574 (-6840 4760);
PAINT MONO (-6840 4760);
DISPLAY INVISIBLE (-6840 4760);
FORCEPROP 1 LASTPIN (-6850 4750) BN 14
J 0
(-6862 4758);
DISPLAY 0.680851 (-6862 4758);
PAINT GREEN (-6862 4758);
FORCEPROP 2 LAST CDS_LIB standard
J 0
(-6800 4750);
DISPLAY INVISIBLE (-6800 4750);
FORCEPROP 1 LAST BODY_TYPE PLUMBING
J 0
(-6800 4800);
DISPLAY 0.872340 (-6800 4800);
PAINT GREEN (-6800 4800);
DISPLAY INVISIBLE (-6800 4800);
FORCEPROP 1 LAST HDL_TAP TRUE
J 0
(-6475 4625);
DISPLAY 0.872340 (-6475 4625);
DISPLAY INVISIBLE (-6475 4625);
FORCEPROP 1 LAST PATH I14
J 0
(-6802 4750);
DISPLAY 0.872340 (-6802 4750);
PAINT GREEN (-6802 4750);
DISPLAY INVISIBLE (-6802 4750);
FORCEADD TAP..1
(-6600 4850);
FORCEPROP 3 LASTPIN (-6650 4850) SIG_NAME P5E_CPU1_P1_TX_C_DP<14>
J 0
(-6640 4860);
DISPLAY 0.659574 (-6640 4860);
PAINT MONO (-6640 4860);
DISPLAY INVISIBLE (-6640 4860);
FORCEPROP 1 LASTPIN (-6650 4850) BN 14
J 0
(-6662 4858);
DISPLAY 0.680851 (-6662 4858);
PAINT GREEN (-6662 4858);
FORCEPROP 2 LAST CDS_LIB standard
J 0
(-6600 4850);
DISPLAY INVISIBLE (-6600 4850);
FORCEPROP 1 LAST BODY_TYPE PLUMBING
J 0
(-6600 4900);
DISPLAY 0.872340 (-6600 4900);
PAINT GREEN (-6600 4900);
DISPLAY INVISIBLE (-6600 4900);
FORCEPROP 1 LAST HDL_TAP TRUE
J 0
(-6275 4725);
DISPLAY 0.872340 (-6275 4725);
DISPLAY INVISIBLE (-6275 4725);
FORCEPROP 1 LAST PATH I15
J 0
(-6602 4850);
DISPLAY 0.872340 (-6602 4850);
PAINT GREEN (-6602 4850);
DISPLAY INVISIBLE (-6602 4850);
FORCEADD TAP..1
(-6800 5200);
FORCEPROP 3 LASTPIN (-6850 5200) SIG_NAME P5E_CPU1_P1_TX_C_DN<15>
J 0
(-6840 5210);
DISPLAY 0.659574 (-6840 5210);
PAINT MONO (-6840 5210);
DISPLAY INVISIBLE (-6840 5210);
FORCEPROP 1 LASTPIN (-6850 5200) BN 15
J 0
(-6862 5208);
DISPLAY 0.680851 (-6862 5208);
PAINT GREEN (-6862 5208);
FORCEPROP 2 LAST CDS_LIB standard
J 0
(-6800 5200);
DISPLAY INVISIBLE (-6800 5200);
FORCEPROP 1 LAST BODY_TYPE PLUMBING
J 0
(-6800 5250);
DISPLAY 0.872340 (-6800 5250);
PAINT GREEN (-6800 5250);
DISPLAY INVISIBLE (-6800 5250);
FORCEPROP 1 LAST HDL_TAP TRUE
J 0
(-6475 5075);
DISPLAY 0.872340 (-6475 5075);
DISPLAY INVISIBLE (-6475 5075);
FORCEPROP 1 LAST PATH I16
J 0
(-6802 5200);
DISPLAY 0.872340 (-6802 5200);
PAINT GREEN (-6802 5200);
DISPLAY INVISIBLE (-6802 5200);
FORCEADD TAP..1
(-6600 5100);
FORCEPROP 3 LASTPIN (-6650 5100) SIG_NAME P5E_CPU1_P1_TX_C_DP<15>
J 0
(-6640 5110);
DISPLAY 0.659574 (-6640 5110);
PAINT MONO (-6640 5110);
DISPLAY INVISIBLE (-6640 5110);
FORCEPROP 1 LASTPIN (-6650 5100) BN 15
J 0
(-6662 5108);
DISPLAY 0.680851 (-6662 5108);
PAINT GREEN (-6662 5108);
FORCEPROP 2 LAST CDS_LIB standard
J 0
(-6600 5100);
DISPLAY INVISIBLE (-6600 5100);
FORCEPROP 1 LAST BODY_TYPE PLUMBING
J 0
(-6600 5150);
DISPLAY 0.872340 (-6600 5150);
PAINT GREEN (-6600 5150);
DISPLAY INVISIBLE (-6600 5150);
FORCEPROP 1 LAST HDL_TAP TRUE
J 0
(-6275 4975);
DISPLAY 0.872340 (-6275 4975);
DISPLAY INVISIBLE (-6275 4975);
FORCEPROP 1 LAST PATH I17
J 0
(-6602 5100);
DISPLAY 0.872340 (-6602 5100);
PAINT GREEN (-6602 5100);
DISPLAY INVISIBLE (-6602 5100);
FORCEADD OFFPAGE..1
R 2
(-5600 5125);
FORCEPROP 2 LAST $XR0 66 
J 0
(-5414 5125);
DISPLAY 0.638298 (-5414 5125);
PAINT MONO (-5414 5125);
FORCEPROP 2 LAST CDS_LIB standard
J 0
(-5600 5125);
DISPLAY INVISIBLE (-5600 5125);
FORCEPROP 1 LAST OFFPAGE TRUE
J 2
(-5925 5000);
DISPLAY 0.872340 (-5925 5000);
DISPLAY INVISIBLE (-5925 5000);
FORCEPROP 1 LAST COMMENT_BODY TRUE
J 2
(-5725 5025);
DISPLAY 0.872340 (-5725 5025);
PAINT GREEN (-5725 5025);
DISPLAY INVISIBLE (-5725 5025);
FORCEPROP 2 LAST PATH I18
J 0
(-5425 5200);
DISPLAY 0.680851 (-5425 5200);
DISPLAY INVISIBLE (-5425 5200);
FORCEADD OFFPAGE..1
R 2
(-5600 5225);
FORCEPROP 2 LAST $XR0 66 
J 0
(-5414 5225);
DISPLAY 0.638298 (-5414 5225);
PAINT MONO (-5414 5225);
FORCEPROP 2 LAST CDS_LIB standard
J 2
(-5600 5225);
DISPLAY INVISIBLE (-5600 5225);
FORCEPROP 1 LAST OFFPAGE TRUE
J 2
(-5925 5100);
DISPLAY 0.872340 (-5925 5100);
DISPLAY INVISIBLE (-5925 5100);
FORCEPROP 1 LAST COMMENT_BODY TRUE
J 2
(-5725 5125);
DISPLAY 0.872340 (-5725 5125);
PAINT GREEN (-5725 5125);
DISPLAY INVISIBLE (-5725 5125);
FORCEPROP 2 LAST PATH I19
J 0
(-5425 5300);
DISPLAY 0.680851 (-5425 5300);
DISPLAY INVISIBLE (-5425 5300);
FORCEADD TAP..1
(-6800 2750);
FORCEPROP 3 LASTPIN (-6850 2750) SIG_NAME P5E_CPU1_P1_TX_C_DN<8>
J 0
(-6840 2760);
DISPLAY 0.659574 (-6840 2760);
PAINT MONO (-6840 2760);
DISPLAY INVISIBLE (-6840 2760);
FORCEPROP 1 LASTPIN (-6850 2750) BN 8
J 0
(-6862 2758);
DISPLAY 0.680851 (-6862 2758);
PAINT GREEN (-6862 2758);
FORCEPROP 2 LAST CDS_LIB standard
J 0
(-6800 2750);
DISPLAY INVISIBLE (-6800 2750);
FORCEPROP 1 LAST BODY_TYPE PLUMBING
J 0
(-6800 2800);
DISPLAY 0.872340 (-6800 2800);
PAINT GREEN (-6800 2800);
DISPLAY INVISIBLE (-6800 2800);
FORCEPROP 1 LAST HDL_TAP TRUE
J 0
(-6475 2625);
DISPLAY 0.872340 (-6475 2625);
DISPLAY INVISIBLE (-6475 2625);
FORCEPROP 1 LAST PATH I2
J 0
(-6802 2750);
DISPLAY 0.872340 (-6802 2750);
PAINT GREEN (-6802 2750);
DISPLAY INVISIBLE (-6802 2750);
FORCEADD TAP..1
(-2175 2700);
FORCEPROP 3 LASTPIN (-2225 2700) SIG_NAME P5E_CPU1_P1_TX_C_DN<0>
J 0
(-2215 2710);
DISPLAY 0.659574 (-2215 2710);
PAINT MONO (-2215 2710);
DISPLAY INVISIBLE (-2215 2710);
FORCEPROP 1 LASTPIN (-2225 2700) BN 0
J 0
(-2237 2708);
DISPLAY 0.680851 (-2237 2708);
PAINT GREEN (-2237 2708);
FORCEPROP 2 LAST CDS_LIB standard
J 0
(-2175 2700);
DISPLAY INVISIBLE (-2175 2700);
FORCEPROP 1 LAST BODY_TYPE PLUMBING
J 0
(-2175 2750);
DISPLAY 0.872340 (-2175 2750);
PAINT GREEN (-2175 2750);
DISPLAY INVISIBLE (-2175 2750);
FORCEPROP 1 LAST HDL_TAP TRUE
J 0
(-1850 2575);
DISPLAY 0.872340 (-1850 2575);
DISPLAY INVISIBLE (-1850 2575);
FORCEPROP 1 LAST PATH I20
J 0
(-2177 2700);
DISPLAY 0.872340 (-2177 2700);
PAINT GREEN (-2177 2700);
DISPLAY INVISIBLE (-2177 2700);
FORCEADD TAP..1
(-1975 2600);
FORCEPROP 3 LASTPIN (-2025 2600) SIG_NAME P5E_CPU1_P1_TX_C_DP<0>
J 0
(-2015 2610);
DISPLAY 0.659574 (-2015 2610);
PAINT MONO (-2015 2610);
DISPLAY INVISIBLE (-2015 2610);
FORCEPROP 1 LASTPIN (-2025 2600) BN 0
J 0
(-2037 2608);
DISPLAY 0.680851 (-2037 2608);
PAINT GREEN (-2037 2608);
FORCEPROP 2 LAST CDS_LIB standard
J 0
(-1975 2600);
DISPLAY INVISIBLE (-1975 2600);
FORCEPROP 1 LAST BODY_TYPE PLUMBING
J 0
(-1975 2650);
DISPLAY 0.872340 (-1975 2650);
PAINT GREEN (-1975 2650);
DISPLAY INVISIBLE (-1975 2650);
FORCEPROP 1 LAST HDL_TAP TRUE
J 0
(-1650 2475);
DISPLAY 0.872340 (-1650 2475);
DISPLAY INVISIBLE (-1650 2475);
FORCEPROP 1 LAST PATH I21
J 0
(-1977 2600);
DISPLAY 0.872340 (-1977 2600);
PAINT GREEN (-1977 2600);
DISPLAY INVISIBLE (-1977 2600);
FORCEADD TAP..1
(-2175 2950);
FORCEPROP 3 LASTPIN (-2225 2950) SIG_NAME P5E_CPU1_P1_TX_C_DN<1>
J 0
(-2215 2960);
DISPLAY 0.659574 (-2215 2960);
PAINT MONO (-2215 2960);
DISPLAY INVISIBLE (-2215 2960);
FORCEPROP 1 LASTPIN (-2225 2950) BN 1
J 0
(-2237 2958);
DISPLAY 0.680851 (-2237 2958);
PAINT GREEN (-2237 2958);
FORCEPROP 2 LAST CDS_LIB standard
J 0
(-2175 2950);
DISPLAY INVISIBLE (-2175 2950);
FORCEPROP 1 LAST BODY_TYPE PLUMBING
J 0
(-2175 3000);
DISPLAY 0.872340 (-2175 3000);
PAINT GREEN (-2175 3000);
DISPLAY INVISIBLE (-2175 3000);
FORCEPROP 1 LAST HDL_TAP TRUE
J 0
(-1850 2825);
DISPLAY 0.872340 (-1850 2825);
DISPLAY INVISIBLE (-1850 2825);
FORCEPROP 1 LAST PATH I22
J 0
(-2177 2950);
DISPLAY 0.872340 (-2177 2950);
PAINT GREEN (-2177 2950);
DISPLAY INVISIBLE (-2177 2950);
FORCEADD TAP..1
(-2175 3400);
FORCEPROP 3 LASTPIN (-2225 3400) SIG_NAME P5E_CPU1_P1_TX_C_DN<2>
J 0
(-2215 3410);
DISPLAY 0.659574 (-2215 3410);
PAINT MONO (-2215 3410);
DISPLAY INVISIBLE (-2215 3410);
FORCEPROP 1 LASTPIN (-2225 3400) BN 2
J 0
(-2237 3408);
DISPLAY 0.680851 (-2237 3408);
PAINT GREEN (-2237 3408);
FORCEPROP 2 LAST CDS_LIB standard
J 0
(-2175 3400);
DISPLAY INVISIBLE (-2175 3400);
FORCEPROP 1 LAST BODY_TYPE PLUMBING
J 0
(-2175 3450);
DISPLAY 0.872340 (-2175 3450);
PAINT GREEN (-2175 3450);
DISPLAY INVISIBLE (-2175 3450);
FORCEPROP 1 LAST HDL_TAP TRUE
J 0
(-1850 3275);
DISPLAY 0.872340 (-1850 3275);
DISPLAY INVISIBLE (-1850 3275);
FORCEPROP 1 LAST PATH I23
J 0
(-2177 3400);
DISPLAY 0.872340 (-2177 3400);
PAINT GREEN (-2177 3400);
DISPLAY INVISIBLE (-2177 3400);
FORCEADD TAP..1
(-1975 3050);
FORCEPROP 3 LASTPIN (-2025 3050) SIG_NAME P5E_CPU1_P1_TX_C_DP<1>
J 0
(-2015 3060);
DISPLAY 0.659574 (-2015 3060);
PAINT MONO (-2015 3060);
DISPLAY INVISIBLE (-2015 3060);
FORCEPROP 1 LASTPIN (-2025 3050) BN 1
J 0
(-2037 3058);
DISPLAY 0.680851 (-2037 3058);
PAINT GREEN (-2037 3058);
FORCEPROP 2 LAST CDS_LIB standard
J 0
(-1975 3050);
DISPLAY INVISIBLE (-1975 3050);
FORCEPROP 1 LAST BODY_TYPE PLUMBING
J 0
(-1975 3100);
DISPLAY 0.872340 (-1975 3100);
PAINT GREEN (-1975 3100);
DISPLAY INVISIBLE (-1975 3100);
FORCEPROP 1 LAST HDL_TAP TRUE
J 0
(-1650 2925);
DISPLAY 0.872340 (-1650 2925);
DISPLAY INVISIBLE (-1650 2925);
FORCEPROP 1 LAST PATH I24
J 0
(-1977 3050);
DISPLAY 0.872340 (-1977 3050);
PAINT GREEN (-1977 3050);
DISPLAY INVISIBLE (-1977 3050);
FORCEADD TAP..1
(-1975 3300);
FORCEPROP 3 LASTPIN (-2025 3300) SIG_NAME P5E_CPU1_P1_TX_C_DP<2>
J 0
(-2015 3310);
DISPLAY 0.659574 (-2015 3310);
PAINT MONO (-2015 3310);
DISPLAY INVISIBLE (-2015 3310);
FORCEPROP 1 LASTPIN (-2025 3300) BN 2
J 0
(-2037 3308);
DISPLAY 0.680851 (-2037 3308);
PAINT GREEN (-2037 3308);
FORCEPROP 2 LAST CDS_LIB standard
J 0
(-1975 3300);
DISPLAY INVISIBLE (-1975 3300);
FORCEPROP 1 LAST BODY_TYPE PLUMBING
J 0
(-1975 3350);
DISPLAY 0.872340 (-1975 3350);
PAINT GREEN (-1975 3350);
DISPLAY INVISIBLE (-1975 3350);
FORCEPROP 1 LAST HDL_TAP TRUE
J 0
(-1650 3175);
DISPLAY 0.872340 (-1650 3175);
DISPLAY INVISIBLE (-1650 3175);
FORCEPROP 1 LAST PATH I25
J 0
(-1977 3300);
DISPLAY 0.872340 (-1977 3300);
PAINT GREEN (-1977 3300);
DISPLAY INVISIBLE (-1977 3300);
FORCEADD TAP..1
(-2175 3750);
FORCEPROP 3 LASTPIN (-2225 3750) SIG_NAME P5E_CPU1_P1_TX_C_DN<3>
J 0
(-2215 3760);
DISPLAY 0.659574 (-2215 3760);
PAINT MONO (-2215 3760);
DISPLAY INVISIBLE (-2215 3760);
FORCEPROP 1 LASTPIN (-2225 3750) BN 3
J 0
(-2237 3758);
DISPLAY 0.680851 (-2237 3758);
PAINT GREEN (-2237 3758);
FORCEPROP 2 LAST CDS_LIB standard
J 0
(-2175 3750);
DISPLAY INVISIBLE (-2175 3750);
FORCEPROP 1 LAST BODY_TYPE PLUMBING
J 0
(-2175 3800);
DISPLAY 0.872340 (-2175 3800);
PAINT GREEN (-2175 3800);
DISPLAY INVISIBLE (-2175 3800);
FORCEPROP 1 LAST HDL_TAP TRUE
J 0
(-1850 3625);
DISPLAY 0.872340 (-1850 3625);
DISPLAY INVISIBLE (-1850 3625);
FORCEPROP 1 LAST PATH I26
J 0
(-2177 3750);
DISPLAY 0.872340 (-2177 3750);
PAINT GREEN (-2177 3750);
DISPLAY INVISIBLE (-2177 3750);
FORCEADD TAP..1
(-1975 3650);
FORCEPROP 3 LASTPIN (-2025 3650) SIG_NAME P5E_CPU1_P1_TX_C_DP<3>
J 0
(-2015 3660);
DISPLAY 0.659574 (-2015 3660);
PAINT MONO (-2015 3660);
DISPLAY INVISIBLE (-2015 3660);
FORCEPROP 1 LASTPIN (-2025 3650) BN 3
J 0
(-2037 3658);
DISPLAY 0.680851 (-2037 3658);
PAINT GREEN (-2037 3658);
FORCEPROP 2 LAST CDS_LIB standard
J 0
(-1975 3650);
DISPLAY INVISIBLE (-1975 3650);
FORCEPROP 1 LAST BODY_TYPE PLUMBING
J 0
(-1975 3700);
DISPLAY 0.872340 (-1975 3700);
PAINT GREEN (-1975 3700);
DISPLAY INVISIBLE (-1975 3700);
FORCEPROP 1 LAST HDL_TAP TRUE
J 0
(-1650 3525);
DISPLAY 0.872340 (-1650 3525);
DISPLAY INVISIBLE (-1650 3525);
FORCEPROP 1 LAST PATH I27
J 0
(-1977 3650);
DISPLAY 0.872340 (-1977 3650);
PAINT GREEN (-1977 3650);
DISPLAY INVISIBLE (-1977 3650);
FORCEADD TAP..1
(-2175 4100);
FORCEPROP 3 LASTPIN (-2225 4100) SIG_NAME P5E_CPU1_P1_TX_C_DN<4>
J 0
(-2215 4110);
DISPLAY 0.659574 (-2215 4110);
PAINT MONO (-2215 4110);
DISPLAY INVISIBLE (-2215 4110);
FORCEPROP 1 LASTPIN (-2225 4100) BN 4
J 0
(-2237 4108);
DISPLAY 0.680851 (-2237 4108);
PAINT GREEN (-2237 4108);
FORCEPROP 2 LAST CDS_LIB standard
J 0
(-2175 4100);
DISPLAY INVISIBLE (-2175 4100);
FORCEPROP 1 LAST BODY_TYPE PLUMBING
J 0
(-2175 4150);
DISPLAY 0.872340 (-2175 4150);
PAINT GREEN (-2175 4150);
DISPLAY INVISIBLE (-2175 4150);
FORCEPROP 1 LAST HDL_TAP TRUE
J 0
(-1850 3975);
DISPLAY 0.872340 (-1850 3975);
DISPLAY INVISIBLE (-1850 3975);
FORCEPROP 1 LAST PATH I28
J 0
(-2177 4100);
DISPLAY 0.872340 (-2177 4100);
PAINT GREEN (-2177 4100);
DISPLAY INVISIBLE (-2177 4100);
FORCEADD TAP..1
(-2175 4450);
FORCEPROP 3 LASTPIN (-2225 4450) SIG_NAME P5E_CPU1_P1_TX_C_DN<5>
J 0
(-2215 4460);
DISPLAY 0.659574 (-2215 4460);
PAINT MONO (-2215 4460);
DISPLAY INVISIBLE (-2215 4460);
FORCEPROP 1 LASTPIN (-2225 4450) BN 5
J 0
(-2237 4458);
DISPLAY 0.680851 (-2237 4458);
PAINT GREEN (-2237 4458);
FORCEPROP 2 LAST CDS_LIB standard
J 0
(-2175 4450);
DISPLAY INVISIBLE (-2175 4450);
FORCEPROP 1 LAST BODY_TYPE PLUMBING
J 0
(-2175 4500);
DISPLAY 0.872340 (-2175 4500);
PAINT GREEN (-2175 4500);
DISPLAY INVISIBLE (-2175 4500);
FORCEPROP 1 LAST HDL_TAP TRUE
J 0
(-1850 4325);
DISPLAY 0.872340 (-1850 4325);
DISPLAY INVISIBLE (-1850 4325);
FORCEPROP 1 LAST PATH I29
J 0
(-2177 4450);
DISPLAY 0.872340 (-2177 4450);
PAINT GREEN (-2177 4450);
DISPLAY INVISIBLE (-2177 4450);
FORCEADD TAP..1
(-6600 2650);
FORCEPROP 3 LASTPIN (-6650 2650) SIG_NAME P5E_CPU1_P1_TX_C_DP<8>
J 0
(-6640 2660);
DISPLAY 0.659574 (-6640 2660);
PAINT MONO (-6640 2660);
DISPLAY INVISIBLE (-6640 2660);
FORCEPROP 1 LASTPIN (-6650 2650) BN 8
J 0
(-6662 2658);
DISPLAY 0.680851 (-6662 2658);
PAINT GREEN (-6662 2658);
FORCEPROP 2 LAST CDS_LIB standard
J 0
(-6600 2650);
DISPLAY INVISIBLE (-6600 2650);
FORCEPROP 1 LAST BODY_TYPE PLUMBING
J 0
(-6600 2700);
DISPLAY 0.872340 (-6600 2700);
PAINT GREEN (-6600 2700);
DISPLAY INVISIBLE (-6600 2700);
FORCEPROP 1 LAST HDL_TAP TRUE
J 0
(-6275 2525);
DISPLAY 0.872340 (-6275 2525);
DISPLAY INVISIBLE (-6275 2525);
FORCEPROP 1 LAST PATH I3
J 0
(-6602 2650);
DISPLAY 0.872340 (-6602 2650);
PAINT GREEN (-6602 2650);
DISPLAY INVISIBLE (-6602 2650);
FORCEADD TAP..1
(-1975 4000);
FORCEPROP 3 LASTPIN (-2025 4000) SIG_NAME P5E_CPU1_P1_TX_C_DP<4>
J 0
(-2015 4010);
DISPLAY 0.659574 (-2015 4010);
PAINT MONO (-2015 4010);
DISPLAY INVISIBLE (-2015 4010);
FORCEPROP 1 LASTPIN (-2025 4000) BN 4
J 0
(-2037 4008);
DISPLAY 0.680851 (-2037 4008);
PAINT GREEN (-2037 4008);
FORCEPROP 2 LAST CDS_LIB standard
J 0
(-1975 4000);
DISPLAY INVISIBLE (-1975 4000);
FORCEPROP 1 LAST BODY_TYPE PLUMBING
J 0
(-1975 4050);
DISPLAY 0.872340 (-1975 4050);
PAINT GREEN (-1975 4050);
DISPLAY INVISIBLE (-1975 4050);
FORCEPROP 1 LAST HDL_TAP TRUE
J 0
(-1650 3875);
DISPLAY 0.872340 (-1650 3875);
DISPLAY INVISIBLE (-1650 3875);
FORCEPROP 1 LAST PATH I30
J 0
(-1977 4000);
DISPLAY 0.872340 (-1977 4000);
PAINT GREEN (-1977 4000);
DISPLAY INVISIBLE (-1977 4000);
FORCEADD TAP..1
(-1975 4350);
FORCEPROP 3 LASTPIN (-2025 4350) SIG_NAME P5E_CPU1_P1_TX_C_DP<5>
J 0
(-2015 4360);
DISPLAY 0.659574 (-2015 4360);
PAINT MONO (-2015 4360);
DISPLAY INVISIBLE (-2015 4360);
FORCEPROP 1 LASTPIN (-2025 4350) BN 5
J 0
(-2037 4358);
DISPLAY 0.680851 (-2037 4358);
PAINT GREEN (-2037 4358);
FORCEPROP 2 LAST CDS_LIB standard
J 0
(-1975 4350);
DISPLAY INVISIBLE (-1975 4350);
FORCEPROP 1 LAST BODY_TYPE PLUMBING
J 0
(-1975 4400);
DISPLAY 0.872340 (-1975 4400);
PAINT GREEN (-1975 4400);
DISPLAY INVISIBLE (-1975 4400);
FORCEPROP 1 LAST HDL_TAP TRUE
J 0
(-1650 4225);
DISPLAY 0.872340 (-1650 4225);
DISPLAY INVISIBLE (-1650 4225);
FORCEPROP 1 LAST PATH I31
J 0
(-1977 4350);
DISPLAY 0.872340 (-1977 4350);
PAINT GREEN (-1977 4350);
DISPLAY INVISIBLE (-1977 4350);
FORCEADD TAP..1
(-2175 4800);
FORCEPROP 3 LASTPIN (-2225 4800) SIG_NAME P5E_CPU1_P1_TX_C_DN<6>
J 0
(-2215 4810);
DISPLAY 0.659574 (-2215 4810);
PAINT MONO (-2215 4810);
DISPLAY INVISIBLE (-2215 4810);
FORCEPROP 1 LASTPIN (-2225 4800) BN 6
J 0
(-2237 4808);
DISPLAY 0.680851 (-2237 4808);
PAINT GREEN (-2237 4808);
FORCEPROP 2 LAST CDS_LIB standard
J 0
(-2175 4800);
DISPLAY INVISIBLE (-2175 4800);
FORCEPROP 1 LAST BODY_TYPE PLUMBING
J 0
(-2175 4850);
DISPLAY 0.872340 (-2175 4850);
PAINT GREEN (-2175 4850);
DISPLAY INVISIBLE (-2175 4850);
FORCEPROP 1 LAST HDL_TAP TRUE
J 0
(-1850 4675);
DISPLAY 0.872340 (-1850 4675);
DISPLAY INVISIBLE (-1850 4675);
FORCEPROP 1 LAST PATH I32
J 0
(-2177 4800);
DISPLAY 0.872340 (-2177 4800);
PAINT GREEN (-2177 4800);
DISPLAY INVISIBLE (-2177 4800);
FORCEADD TAP..1
(-1975 4700);
FORCEPROP 3 LASTPIN (-2025 4700) SIG_NAME P5E_CPU1_P1_TX_C_DP<6>
J 0
(-2015 4710);
DISPLAY 0.659574 (-2015 4710);
PAINT MONO (-2015 4710);
DISPLAY INVISIBLE (-2015 4710);
FORCEPROP 1 LASTPIN (-2025 4700) BN 6
J 0
(-2037 4708);
DISPLAY 0.680851 (-2037 4708);
PAINT GREEN (-2037 4708);
FORCEPROP 2 LAST CDS_LIB standard
J 0
(-1975 4700);
DISPLAY INVISIBLE (-1975 4700);
FORCEPROP 1 LAST BODY_TYPE PLUMBING
J 0
(-1975 4750);
DISPLAY 0.872340 (-1975 4750);
PAINT GREEN (-1975 4750);
DISPLAY INVISIBLE (-1975 4750);
FORCEPROP 1 LAST HDL_TAP TRUE
J 0
(-1650 4575);
DISPLAY 0.872340 (-1650 4575);
DISPLAY INVISIBLE (-1650 4575);
FORCEPROP 1 LAST PATH I33
J 0
(-1977 4700);
DISPLAY 0.872340 (-1977 4700);
PAINT GREEN (-1977 4700);
DISPLAY INVISIBLE (-1977 4700);
FORCEADD TAP..1
(-2175 5150);
FORCEPROP 3 LASTPIN (-2225 5150) SIG_NAME P5E_CPU1_P1_TX_C_DN<7>
J 0
(-2215 5160);
DISPLAY 0.659574 (-2215 5160);
PAINT MONO (-2215 5160);
DISPLAY INVISIBLE (-2215 5160);
FORCEPROP 1 LASTPIN (-2225 5150) BN 7
J 0
(-2237 5158);
DISPLAY 0.680851 (-2237 5158);
PAINT GREEN (-2237 5158);
FORCEPROP 2 LAST CDS_LIB standard
J 0
(-2175 5150);
DISPLAY INVISIBLE (-2175 5150);
FORCEPROP 1 LAST BODY_TYPE PLUMBING
J 0
(-2175 5200);
DISPLAY 0.872340 (-2175 5200);
PAINT GREEN (-2175 5200);
DISPLAY INVISIBLE (-2175 5200);
FORCEPROP 1 LAST HDL_TAP TRUE
J 0
(-1850 5025);
DISPLAY 0.872340 (-1850 5025);
DISPLAY INVISIBLE (-1850 5025);
FORCEPROP 1 LAST PATH I34
J 0
(-2177 5150);
DISPLAY 0.872340 (-2177 5150);
PAINT GREEN (-2177 5150);
DISPLAY INVISIBLE (-2177 5150);
FORCEADD TAP..1
(-1975 5050);
FORCEPROP 3 LASTPIN (-2025 5050) SIG_NAME P5E_CPU1_P1_TX_C_DP<7>
J 0
(-2015 5060);
DISPLAY 0.659574 (-2015 5060);
PAINT MONO (-2015 5060);
DISPLAY INVISIBLE (-2015 5060);
FORCEPROP 1 LASTPIN (-2025 5050) BN 7
J 0
(-2037 5058);
DISPLAY 0.680851 (-2037 5058);
PAINT GREEN (-2037 5058);
FORCEPROP 2 LAST CDS_LIB standard
J 0
(-1975 5050);
DISPLAY INVISIBLE (-1975 5050);
FORCEPROP 1 LAST BODY_TYPE PLUMBING
J 0
(-1975 5100);
DISPLAY 0.872340 (-1975 5100);
PAINT GREEN (-1975 5100);
DISPLAY INVISIBLE (-1975 5100);
FORCEPROP 1 LAST HDL_TAP TRUE
J 0
(-1650 4925);
DISPLAY 0.872340 (-1650 4925);
DISPLAY INVISIBLE (-1650 4925);
FORCEPROP 1 LAST PATH I35
J 0
(-1977 5050);
DISPLAY 0.872340 (-1977 5050);
PAINT GREEN (-1977 5050);
DISPLAY INVISIBLE (-1977 5050);
FORCEADD OFFPAGE..1
R 2
(-975 5075);
FORCEPROP 2 LAST $XR0 66 
J 0
(-789 5075);
DISPLAY 0.638298 (-789 5075);
PAINT MONO (-789 5075);
FORCEPROP 2 LAST CDS_LIB standard
J 0
(-975 5075);
DISPLAY INVISIBLE (-975 5075);
FORCEPROP 1 LAST OFFPAGE TRUE
J 2
(-1300 4950);
DISPLAY 0.872340 (-1300 4950);
DISPLAY INVISIBLE (-1300 4950);
FORCEPROP 1 LAST COMMENT_BODY TRUE
J 2
(-1100 4975);
DISPLAY 0.872340 (-1100 4975);
PAINT GREEN (-1100 4975);
DISPLAY INVISIBLE (-1100 4975);
FORCEPROP 2 LAST PATH I36
J 0
(-800 5150);
DISPLAY 0.680851 (-800 5150);
DISPLAY INVISIBLE (-800 5150);
FORCEADD OFFPAGE..1
R 2
(-975 5175);
FORCEPROP 2 LAST $XR0 66 
J 0
(-789 5175);
DISPLAY 0.638298 (-789 5175);
PAINT MONO (-789 5175);
FORCEPROP 2 LAST CDS_LIB standard
J 2
(-975 5175);
DISPLAY INVISIBLE (-975 5175);
FORCEPROP 1 LAST OFFPAGE TRUE
J 2
(-1300 5050);
DISPLAY 0.872340 (-1300 5050);
DISPLAY INVISIBLE (-1300 5050);
FORCEPROP 1 LAST COMMENT_BODY TRUE
J 2
(-1100 5075);
DISPLAY 0.872340 (-1100 5075);
PAINT GREEN (-1100 5075);
DISPLAY INVISIBLE (-1100 5075);
FORCEPROP 2 LAST PATH I37
J 0
(-800 5250);
DISPLAY 0.680851 (-800 5250);
DISPLAY INVISIBLE (-800 5250);
FORCEADD PT5161LRS..9
(-3200 3900);
FORCEPROP 1 LAST LOCATION U6015
J 0
(-3550 5525);
DISPLAY 0.723404 (-3550 5525);
PAINT GREEN (-3550 5525);
FORCEPROP 0 LAST $SEC 9
J 0
(-3550 5675);
DISPLAY 0.680851 (-3550 5675);
PAINT MONO (-3550 5675);
DISPLAY INVISIBLE (-3550 5675);
FORCEPROP 0 LAST CDS_SEC 9
J 0
(-3550 5675);
DISPLAY 0.680851 (-3550 5675);
DISPLAY INVISIBLE (-3550 5675);
FORCEPROP 0 LASTPIN (-2750 5050) $PN CL35
J 0
(-2740 5060);
DISPLAY 0.680851 (-2740 5060);
PAINT MONO (-2740 5060);
FORCEPROP 0 LASTPIN (-2750 4700) $PN CV35
J 0
(-2740 4710);
DISPLAY 0.680851 (-2740 4710);
PAINT MONO (-2740 4710);
FORCEPROP 0 LASTPIN (-2750 4350) $PN DE35
J 0
(-2740 4360);
DISPLAY 0.680851 (-2740 4360);
PAINT MONO (-2740 4360);
FORCEPROP 0 LASTPIN (-2750 4000) $PN DM35
J 0
(-2740 4010);
DISPLAY 0.680851 (-2740 4010);
PAINT MONO (-2740 4010);
FORCEPROP 0 LASTPIN (-2750 3650) $PN DW35
J 0
(-2740 3660);
DISPLAY 0.680851 (-2740 3660);
PAINT MONO (-2740 3660);
FORCEPROP 0 LASTPIN (-2750 3300) $PN EF35
J 0
(-2740 3310);
DISPLAY 0.680851 (-2740 3310);
PAINT MONO (-2740 3310);
FORCEPROP 0 LASTPIN (-2750 2950) $PN EN35
J 0
(-2740 2960);
DISPLAY 0.680851 (-2740 2960);
PAINT MONO (-2740 2960);
FORCEPROP 0 LASTPIN (-2750 2600) $PN EY35
J 0
(-2740 2610);
DISPLAY 0.680851 (-2740 2610);
PAINT MONO (-2740 2610);
FORCEPROP 0 LASTPIN (-2750 5150) $PN CJ34
J 0
(-2740 5160);
DISPLAY 0.680851 (-2740 5160);
PAINT MONO (-2740 5160);
FORCEPROP 0 LASTPIN (-2750 4800) $PN CT34
J 0
(-2740 4810);
DISPLAY 0.680851 (-2740 4810);
PAINT MONO (-2740 4810);
FORCEPROP 0 LASTPIN (-2750 4450) $PN DC34
J 0
(-2740 4460);
DISPLAY 0.680851 (-2740 4460);
PAINT MONO (-2740 4460);
FORCEPROP 0 LASTPIN (-2750 4100) $PN DK34
J 0
(-2740 4110);
DISPLAY 0.680851 (-2740 4110);
PAINT MONO (-2740 4110);
FORCEPROP 0 LASTPIN (-2750 3750) $PN DU34
J 0
(-2740 3760);
DISPLAY 0.680851 (-2740 3760);
PAINT MONO (-2740 3760);
FORCEPROP 0 LASTPIN (-2750 3400) $PN ED34
J 0
(-2740 3410);
DISPLAY 0.680851 (-2740 3410);
PAINT MONO (-2740 3410);
FORCEPROP 0 LASTPIN (-2750 3050) $PN EL34
J 0
(-2740 3060);
DISPLAY 0.680851 (-2740 3060);
PAINT MONO (-2740 3060);
FORCEPROP 0 LASTPIN (-2750 2700) $PN EV34
J 0
(-2740 2710);
DISPLAY 0.680851 (-2740 2710);
PAINT MONO (-2740 2710);
FORCEPROP 2 LAST PART_TYPE SMLF
J 0
(-3550 5625);
DISPLAY 0.680851 (-3550 5625);
FORCEPROP 2 LAST VALUE PT5161LRS
J 0
(-3550 5575);
DISPLAY 0.680851 (-3550 5575);
FORCEPROP 1 LAST MATERIAL IC
J 0
(-3550 5375);
DISPLAY 0.723404 (-3550 5375);
PAINT GREEN (-3550 5375);
FORCEPROP 1 LAST NEEDS_NO_SIZE TRUE
J 0
(-3200 3900);
DISPLAY 0.723404 (-3200 3900);
PAINT GREEN (-3200 3900);
DISPLAY INVISIBLE (-3200 3900);
FORCEPROP 1 LAST CDS_LMAN_SYM_OUTLINE -350,1450,300,-1400
J 0
(-3200 3900);
DISPLAY 0.468085 (-3200 3900);
PAINT GREEN (-3200 3900);
DISPLAY INVISIBLE (-3200 3900);
FORCEPROP 2 LAST CDS_LIB pure_quanta
J 0
(-3200 3900);
DISPLAY INVISIBLE (-3200 3900);
FORCEPROP 1 LAST PATH I38
J 0
(-3200 3900);
DISPLAY 0.723404 (-3200 3900);
PAINT GREEN (-3200 3900);
DISPLAY INVISIBLE (-3200 3900);
FORCEPROP 1 LAST PART_NUMBER AJ051610U03
J 0
(-3550 5450);
DISPLAY 0.723404 (-3550 5450);
PAINT GREEN (-3550 5450);
DISPLAY INVISIBLE (-3550 5450);
FORCEADD TAP..1
(-6800 3100);
FORCEPROP 3 LASTPIN (-6850 3100) SIG_NAME P5E_CPU1_P1_TX_C_DN<9>
J 0
(-6840 3110);
DISPLAY 0.659574 (-6840 3110);
PAINT MONO (-6840 3110);
DISPLAY INVISIBLE (-6840 3110);
FORCEPROP 1 LASTPIN (-6850 3100) BN 9
J 0
(-6862 3108);
DISPLAY 0.680851 (-6862 3108);
PAINT GREEN (-6862 3108);
FORCEPROP 2 LAST CDS_LIB standard
J 0
(-6800 3100);
DISPLAY INVISIBLE (-6800 3100);
FORCEPROP 1 LAST BODY_TYPE PLUMBING
J 0
(-6800 3150);
DISPLAY 0.872340 (-6800 3150);
PAINT GREEN (-6800 3150);
DISPLAY INVISIBLE (-6800 3150);
FORCEPROP 1 LAST HDL_TAP TRUE
J 0
(-6475 2975);
DISPLAY 0.872340 (-6475 2975);
DISPLAY INVISIBLE (-6475 2975);
FORCEPROP 1 LAST PATH I4
J 0
(-6802 3100);
DISPLAY 0.872340 (-6802 3100);
PAINT GREEN (-6802 3100);
DISPLAY INVISIBLE (-6802 3100);
FORCEADD TAP..1
(-6600 3000);
FORCEPROP 3 LASTPIN (-6650 3000) SIG_NAME P5E_CPU1_P1_TX_C_DP<9>
J 0
(-6640 3010);
DISPLAY 0.659574 (-6640 3010);
PAINT MONO (-6640 3010);
DISPLAY INVISIBLE (-6640 3010);
FORCEPROP 1 LASTPIN (-6650 3000) BN 9
J 0
(-6662 3008);
DISPLAY 0.680851 (-6662 3008);
PAINT GREEN (-6662 3008);
FORCEPROP 2 LAST CDS_LIB standard
J 0
(-6600 3000);
DISPLAY INVISIBLE (-6600 3000);
FORCEPROP 1 LAST BODY_TYPE PLUMBING
J 0
(-6600 3050);
DISPLAY 0.872340 (-6600 3050);
PAINT GREEN (-6600 3050);
DISPLAY INVISIBLE (-6600 3050);
FORCEPROP 1 LAST HDL_TAP TRUE
J 0
(-6275 2875);
DISPLAY 0.872340 (-6275 2875);
DISPLAY INVISIBLE (-6275 2875);
FORCEPROP 1 LAST PATH I5
J 0
(-6602 3000);
DISPLAY 0.872340 (-6602 3000);
PAINT GREEN (-6602 3000);
DISPLAY INVISIBLE (-6602 3000);
FORCEADD TAP..1
(-6600 3350);
FORCEPROP 3 LASTPIN (-6650 3350) SIG_NAME P5E_CPU1_P1_TX_C_DP<10>
J 0
(-6640 3360);
DISPLAY 0.659574 (-6640 3360);
PAINT MONO (-6640 3360);
DISPLAY INVISIBLE (-6640 3360);
FORCEPROP 1 LASTPIN (-6650 3350) BN 10
J 0
(-6662 3358);
DISPLAY 0.680851 (-6662 3358);
PAINT GREEN (-6662 3358);
FORCEPROP 2 LAST CDS_LIB standard
J 0
(-6600 3350);
DISPLAY INVISIBLE (-6600 3350);
FORCEPROP 1 LAST BODY_TYPE PLUMBING
J 0
(-6600 3400);
DISPLAY 0.872340 (-6600 3400);
PAINT GREEN (-6600 3400);
DISPLAY INVISIBLE (-6600 3400);
FORCEPROP 1 LAST HDL_TAP TRUE
J 0
(-6275 3225);
DISPLAY 0.872340 (-6275 3225);
DISPLAY INVISIBLE (-6275 3225);
FORCEPROP 1 LAST PATH I6
J 0
(-6602 3350);
DISPLAY 0.872340 (-6602 3350);
PAINT GREEN (-6602 3350);
DISPLAY INVISIBLE (-6602 3350);
FORCEADD TAP..1
(-6800 3450);
FORCEPROP 3 LASTPIN (-6850 3450) SIG_NAME P5E_CPU1_P1_TX_C_DN<10>
J 0
(-6840 3460);
DISPLAY 0.659574 (-6840 3460);
PAINT MONO (-6840 3460);
DISPLAY INVISIBLE (-6840 3460);
FORCEPROP 1 LASTPIN (-6850 3450) BN 10
J 0
(-6862 3458);
DISPLAY 0.680851 (-6862 3458);
PAINT GREEN (-6862 3458);
FORCEPROP 2 LAST CDS_LIB standard
J 0
(-6800 3450);
DISPLAY INVISIBLE (-6800 3450);
FORCEPROP 1 LAST BODY_TYPE PLUMBING
J 0
(-6800 3500);
DISPLAY 0.872340 (-6800 3500);
PAINT GREEN (-6800 3500);
DISPLAY INVISIBLE (-6800 3500);
FORCEPROP 1 LAST HDL_TAP TRUE
J 0
(-6475 3325);
DISPLAY 0.872340 (-6475 3325);
DISPLAY INVISIBLE (-6475 3325);
FORCEPROP 1 LAST PATH I7
J 0
(-6802 3450);
DISPLAY 0.872340 (-6802 3450);
PAINT GREEN (-6802 3450);
DISPLAY INVISIBLE (-6802 3450);
FORCEADD TAP..1
(-6800 3800);
FORCEPROP 3 LASTPIN (-6850 3800) SIG_NAME P5E_CPU1_P1_TX_C_DN<11>
J 0
(-6840 3810);
DISPLAY 0.659574 (-6840 3810);
PAINT MONO (-6840 3810);
DISPLAY INVISIBLE (-6840 3810);
FORCEPROP 1 LASTPIN (-6850 3800) BN 11
J 0
(-6862 3808);
DISPLAY 0.680851 (-6862 3808);
PAINT GREEN (-6862 3808);
FORCEPROP 2 LAST CDS_LIB standard
J 0
(-6800 3800);
DISPLAY INVISIBLE (-6800 3800);
FORCEPROP 1 LAST BODY_TYPE PLUMBING
J 0
(-6800 3850);
DISPLAY 0.872340 (-6800 3850);
PAINT GREEN (-6800 3850);
DISPLAY INVISIBLE (-6800 3850);
FORCEPROP 1 LAST HDL_TAP TRUE
J 0
(-6475 3675);
DISPLAY 0.872340 (-6475 3675);
DISPLAY INVISIBLE (-6475 3675);
FORCEPROP 1 LAST PATH I8
J 0
(-6802 3800);
DISPLAY 0.872340 (-6802 3800);
PAINT GREEN (-6802 3800);
DISPLAY INVISIBLE (-6802 3800);
FORCEADD TAP..1
(-6600 3700);
FORCEPROP 3 LASTPIN (-6650 3700) SIG_NAME P5E_CPU1_P1_TX_C_DP<11>
J 0
(-6640 3710);
DISPLAY 0.659574 (-6640 3710);
PAINT MONO (-6640 3710);
DISPLAY INVISIBLE (-6640 3710);
FORCEPROP 1 LASTPIN (-6650 3700) BN 11
J 0
(-6662 3708);
DISPLAY 0.680851 (-6662 3708);
PAINT GREEN (-6662 3708);
FORCEPROP 2 LAST CDS_LIB standard
J 0
(-6600 3700);
DISPLAY INVISIBLE (-6600 3700);
FORCEPROP 1 LAST BODY_TYPE PLUMBING
J 0
(-6600 3750);
DISPLAY 0.872340 (-6600 3750);
PAINT GREEN (-6600 3750);
DISPLAY INVISIBLE (-6600 3750);
FORCEPROP 1 LAST HDL_TAP TRUE
J 0
(-6275 3575);
DISPLAY 0.872340 (-6275 3575);
DISPLAY INVISIBLE (-6275 3575);
FORCEPROP 1 LAST PATH I9
J 0
(-6602 3700);
DISPLAY 0.872340 (-6602 3700);
PAINT GREEN (-6602 3700);
DISPLAY INVISIBLE (-6602 3700);
FORCEADD QUANTA_TITLE_BLOCK_C..1
(0 0);
FORCEPROP 0 LAST CDS_CON_LAST_MODIFIED Thu Sep 14 16:12:50 2023
J 0
(-1885 15);
DISPLAY INVISIBLE (-1885 15);
FORCEPROP 1 LAST CUSTOM_TXT_CDS <CON_LAST_MODIFIED>
J 0
(-1885 15);
DISPLAY 0.978723 (-1885 15);
FORCEPROP 2 LAST CUSTOM_TXT_CDS <XR_PAGE_TITLE>
J 0
(-7890 5250);
DISPLAY 0.638298 (-7890 5250);
PAINT PINK (-7890 5250);
DISPLAY INVISIBLE (-7890 5250);
FORCEPROP 1 LAST CUSTOM_TXT_CDS <NAME_2>
J 0
(-3175 50);
FORCEPROP 1 LAST CUSTOM_TXT_CDS <NAME_1>
J 0
(-3175 175);
FORCEPROP 1 LAST CUSTOM_TXT_CDS <Q_NUMBER>
J 0
(-1403 103);
DISPLAY 1.212766 (-1403 103);
FORCEPROP 1 LAST CUSTOM_TXT_CDS <Q_PROJ>
J 0
(-2382 102);
DISPLAY 1.212766 (-2382 102);
FORCEPROP 1 LAST CUSTOM_TXT_CDS <Q_REV>
J 0
(-184 103);
DISPLAY 1.212766 (-184 103);
FORCEPROP 1 LAST CUSTOM_TXT_CDS <CON_PAGE_NUM> OF <CON_TOTAL_PAGES>
J 0
(-446 18);
DISPLAY 0.978723 (-446 18);
FORCEPROP 1 LAST Q_TITLE RETIMER_CPU1_P1(1)
J 0
(-9366 26);
DISPLAY 2.446809 (-9366 26);
PAINT GREEN (-9366 26);
FORCEPROP 1 LAST CDS_LMAN_SYM_OUTLINE -9475,6775,100,-125
J 0
(0 0);
DISPLAY 0.468085 (0 0);
PAINT GREEN (0 0);
DISPLAY INVISIBLE (0 0);
FORCEPROP 2 LAST CDS_LIB pure_quanta
J 0
(0 0);
DISPLAY INVISIBLE (0 0);
FORCEPROP 2 LAST PAGE_BORDER TRUE
J 0
(-7890 5250);
DISPLAY 0.638298 (-7890 5250);
PAINT PINK (-7890 5250);
DISPLAY INVISIBLE (-7890 5250);
FORCEPROP 2 LAST CDS_XR_PAGE_TITLE CR-328 : @T6G_MB_LIB.T6G(SCH_1):PAGE328
J 0
(-7890 5250);
DISPLAY 0.638298 (-7890 5250);
PAINT PINK (-7890 5250);
DISPLAY INVISIBLE (-7890 5250);
FORCEPROP 1 LAST Q_DEPT BU9
J 1
(-3763 49);
DISPLAY 1.957447 (-3763 49);
PAINT GREEN (-3763 49);
DISPLAY INVISIBLE (-3763 49);
FORCEPROP 1 LAST COMMENT_BODY TRUE
J 0
(12 -13);
DISPLAY 0.978723 (12 -13);
PAINT GREEN (12 -13);
DISPLAY INVISIBLE (12 -13);
WIRE 17 -1 (-6750 3825)(-6750 4175);
WIRE 17 -1 (-6750 3825)(-6750 3475);
WIRE 17 -1 (-6750 4525)(-6750 4175);
WIRE 17 -1 (-6750 4775)(-6750 4525);
WIRE 17 -1 (-6750 3475)(-6750 3125);
WIRE 17 -1 (-6750 3125)(-6750 2775);
WIRE 17 -1 (-6750 5225)(-6750 4775);
WIRE 17 -1 (-5650 5225)(-6750 5225);
FORCEPROP 2 LAST SIG_NAME P5E_CPU1_P1_TX_C_DN<15:8>
J 0
(-6485 5235);
DISPLAY 0.680851 (-6485 5235);
PAINT WHITE (-6485 5235);
WIRE 17 -1 (-6550 3725)(-6550 4075);
WIRE 17 -1 (-6550 3725)(-6550 3375);
WIRE 17 -1 (-6550 4425)(-6550 4075);
WIRE 17 -1 (-6550 4875)(-6550 4425);
WIRE 17 -1 (-6550 3375)(-6550 3025);
WIRE 17 -1 (-6550 3025)(-6550 2675);
WIRE 17 -1 (-6550 5125)(-6550 4875);
WIRE 17 -1 (-6550 5125)(-5650 5125);
FORCEPROP 2 LAST SIG_NAME P5E_CPU1_P1_TX_C_DP<15:8>
J 0
(-6485 5135);
DISPLAY 0.680851 (-6485 5135);
PAINT WHITE (-6485 5135);
WIRE 17 -1 (-1925 5075)(-1925 4725);
WIRE 17 -1 (-1925 5075)(-1025 5075);
FORCEPROP 2 LAST SIG_NAME P5E_CPU1_P1_TX_C_DP<7:0>
J 0
(-1860 5085);
DISPLAY 0.680851 (-1860 5085);
PAINT WHITE (-1860 5085);
WIRE 17 -1 (-1925 4725)(-1925 4375);
WIRE 17 -1 (-1925 4375)(-1925 4025);
WIRE 17 -1 (-1925 3675)(-1925 4025);
WIRE 17 -1 (-1925 3675)(-1925 3325);
WIRE 17 -1 (-1925 3325)(-1925 3075);
WIRE 17 -1 (-1925 3075)(-1925 2625);
WIRE 17 -1 (-2125 5175)(-2125 4825);
WIRE 17 -1 (-2125 5175)(-1025 5175);
FORCEPROP 2 LAST SIG_NAME P5E_CPU1_P1_TX_C_DN<7:0>
J 0
(-1860 5185);
DISPLAY 0.680851 (-1860 5185);
PAINT WHITE (-1860 5185);
WIRE 17 -1 (-2125 3775)(-2125 3425);
WIRE 17 -1 (-2125 3775)(-2125 4125);
WIRE 17 -1 (-2125 3425)(-2125 2975);
WIRE 17 -1 (-2125 2975)(-2125 2725);
WIRE 17 -1 (-2125 4475)(-2125 4125);
WIRE 17 -1 (-2125 4825)(-2125 4475);
WIRE 16 -1 (-7375 5200)(-6850 5200);
WIRE 16 -1 (-7375 5100)(-6650 5100);
WIRE 16 -1 (-7375 4850)(-6650 4850);
WIRE 16 -1 (-6850 4750)(-7375 4750);
WIRE 16 -1 (-7375 4400)(-6650 4400);
WIRE 16 -1 (-7375 4500)(-6850 4500);
WIRE 16 -1 (-2750 4100)(-2225 4100);
WIRE 16 -1 (-2750 3300)(-2025 3300);
WIRE 16 -1 (-2025 3050)(-2750 3050);
WIRE 16 -1 (-2225 2950)(-2750 2950);
WIRE 16 -1 (-2750 2700)(-2225 2700);
WIRE 16 -1 (-2750 2600)(-2025 2600);
WIRE 16 -1 (-2750 5150)(-2225 5150);
WIRE 16 -1 (-2750 4450)(-2225 4450);
WIRE 16 -1 (-2750 3750)(-2225 3750);
WIRE 16 -1 (-2750 3400)(-2225 3400);
WIRE 16 -1 (-2750 4800)(-2225 4800);
WIRE 16 -1 (-7375 3350)(-6650 3350);
WIRE 16 -1 (-7375 3000)(-6650 3000);
WIRE 16 -1 (-7375 3700)(-6650 3700);
WIRE 16 -1 (-7375 2650)(-6650 2650);
WIRE 16 -1 (-7375 2750)(-6850 2750);
WIRE 16 -1 (-7375 3450)(-6850 3450);
WIRE 16 -1 (-7375 3100)(-6850 3100);
WIRE 16 -1 (-2750 5050)(-2025 5050);
WIRE 16 -1 (-2750 3650)(-2025 3650);
WIRE 16 -1 (-2750 4000)(-2025 4000);
WIRE 16 -1 (-2750 4350)(-2025 4350);
WIRE 16 -1 (-2750 4700)(-2025 4700);
WIRE 16 -1 (-7375 4050)(-6650 4050);
WIRE 16 -1 (-7375 3800)(-6850 3800);
WIRE 16 -1 (-7375 4150)(-6850 4150);
FORCENOTE
CPU TO RETIMER
(-8250 1800) 0;
DISPLAY LEFT (-8250 1800);
DISPLAY 3.148936 (-8250 1800);
FORCENOTE
CPU TO RETIMER
(-3650 1800) 0;
DISPLAY LEFT (-3650 1800);
DISPLAY 3.148936 (-3650 1800);
FORCENOTE
P5E_CPU1_P1_TX_C_DP/DN<0-15> LANE REVERSAL
(-8975 6350) 0;
DISPLAY LEFT (-8975 6350);
DISPLAY 2.000000 (-8975 6350);
FORCENOTE
P/N SWAP
(-6375 2975) 0;
DISPLAY LEFT (-6375 2975);
DISPLAY 1.021277 (-6375 2975);
FORCENOTE
P/N SWAP
(-6375 2650) 0;
DISPLAY LEFT (-6375 2650);
DISPLAY 1.021277 (-6375 2650);
FORCENOTE
P/N SWAP
(-6400 3350) 0;
DISPLAY LEFT (-6400 3350);
DISPLAY 1.021277 (-6400 3350);
FORCENOTE
P/N SWAP
(-1775 2625) 0;
DISPLAY LEFT (-1775 2625);
DISPLAY 1.021277 (-1775 2625);
FORCENOTE
P/N SWAP
(-6375 3700) 0;
DISPLAY LEFT (-6375 3700);
DISPLAY 1.021277 (-6375 3700);
FORCENOTE
P/N SWAP
(-1800 4975) 0;
DISPLAY LEFT (-1800 4975);
DISPLAY 1.021277 (-1800 4975);
FORCENOTE
P/N SWAP
(-6475 4100) 0;
DISPLAY LEFT (-6475 4100);
DISPLAY 1.021277 (-6475 4100);
FORCENOTE
P/N SWAP
(-1800 3325) 0;
DISPLAY LEFT (-1800 3325);
DISPLAY 1.021277 (-1800 3325);
FORCENOTE
P/N SWAP
(-1775 3675) 0;
DISPLAY LEFT (-1775 3675);
DISPLAY 1.021277 (-1775 3675);
FORCENOTE
P/N SWAP
(-1825 4025) 0;
DISPLAY LEFT (-1825 4025);
DISPLAY 1.021277 (-1825 4025);
FORCENOTE
P/N SWAP
(-1800 4375) 0;
DISPLAY LEFT (-1800 4375);
DISPLAY 1.021277 (-1800 4375);
FORCENOTE
P/N SWAP
(-1800 4675) 0;
DISPLAY LEFT (-1800 4675);
DISPLAY 1.021277 (-1800 4675);
FORCENOTE
P/N SWAP
(-6450 5025) 0;
DISPLAY LEFT (-6450 5025);
DISPLAY 1.021277 (-6450 5025);
FORCENOTE
P/N SWAP
(-6475 4425) 0;
DISPLAY LEFT (-6475 4425);
DISPLAY 1.021277 (-6475 4425);
QUIT
